FILE_TYPE=LIBRARY_PARTS;
primitive 'SCONN60_ASP21410801';
  pin
    '1':
      PIN_NUMBER='(1)';
      BIDIRECTIONAL='TRUE';
      INPUT_LOAD='(-0.01,0.01)';
      OUTPUT_LOAD='(1.0,-1.0)';
    '2':
      PIN_NUMBER='(2)';
      BIDIRECTIONAL='TRUE';
      INPUT_LOAD='(-0.01,0.01)';
      OUTPUT_LOAD='(1.0,-1.0)';
    '3':
      PIN_NUMBER='(3)';
      BIDIRECTIONAL='TRUE';
      INPUT_LOAD='(-0.01,0.01)';
      OUTPUT_LOAD='(1.0,-1.0)';
    '4':
      PIN_NUMBER='(4)';
      BIDIRECTIONAL='TRUE';
      INPUT_LOAD='(-0.01,0.01)';
      OUTPUT_LOAD='(1.0,-1.0)';
    '5':
      PIN_NUMBER='(5)';
      BIDIRECTIONAL='TRUE';
      INPUT_LOAD='(-0.01,0.01)';
      OUTPUT_LOAD='(1.0,-1.0)';
    '6':
      PIN_NUMBER='(6)';
      BIDIRECTIONAL='TRUE';
      INPUT_LOAD='(-0.01,0.01)';
      OUTPUT_LOAD='(1.0,-1.0)';
    '7':
      PIN_NUMBER='(7)';
      BIDIRECTIONAL='TRUE';
      INPUT_LOAD='(-0.01,0.01)';
      OUTPUT_LOAD='(1.0,-1.0)';
    '8':
      PIN_NUMBER='(8)';
      BIDIRECTIONAL='TRUE';
      INPUT_LOAD='(-0.01,0.01)';
      OUTPUT_LOAD='(1.0,-1.0)';
    '9':
      PIN_NUMBER='(9)';
      BIDIRECTIONAL='TRUE';
      INPUT_LOAD='(-0.01,0.01)';
      OUTPUT_LOAD='(1.0,-1.0)';
    '10':
      PIN_NUMBER='(10)';
      BIDIRECTIONAL='TRUE';
      INPUT_LOAD='(-0.01,0.01)';
      OUTPUT_LOAD='(1.0,-1.0)';
    '11':
      PIN_NUMBER='(11)';
      BIDIRECTIONAL='TRUE';
      INPUT_LOAD='(-0.01,0.01)';
      OUTPUT_LOAD='(1.0,-1.0)';
    '12':
      PIN_NUMBER='(12)';
      BIDIRECTIONAL='TRUE';
      INPUT_LOAD='(-0.01,0.01)';
      OUTPUT_LOAD='(1.0,-1.0)';
    '13':
      PIN_NUMBER='(13)';
      BIDIRECTIONAL='TRUE';
      INPUT_LOAD='(-0.01,0.01)';
      OUTPUT_LOAD='(1.0,-1.0)';
    '14':
      PIN_NUMBER='(14)';
      BIDIRECTIONAL='TRUE';
      INPUT_LOAD='(-0.01,0.01)';
      OUTPUT_LOAD='(1.0,-1.0)';
    '15':
      PIN_NUMBER='(15)';
      BIDIRECTIONAL='TRUE';
      INPUT_LOAD='(-0.01,0.01)';
      OUTPUT_LOAD='(1.0,-1.0)';
    '16':
      PIN_NUMBER='(16)';
      BIDIRECTIONAL='TRUE';
      INPUT_LOAD='(-0.01,0.01)';
      OUTPUT_LOAD='(1.0,-1.0)';
    '17':
      PIN_NUMBER='(17)';
      BIDIRECTIONAL='TRUE';
      INPUT_LOAD='(-0.01,0.01)';
      OUTPUT_LOAD='(1.0,-1.0)';
    '18':
      PIN_NUMBER='(18)';
      BIDIRECTIONAL='TRUE';
      INPUT_LOAD='(-0.01,0.01)';
      OUTPUT_LOAD='(1.0,-1.0)';
    '19':
      PIN_NUMBER='(19)';
      BIDIRECTIONAL='TRUE';
      INPUT_LOAD='(-0.01,0.01)';
      OUTPUT_LOAD='(1.0,-1.0)';
    '20':
      PIN_NUMBER='(20)';
      BIDIRECTIONAL='TRUE';
      INPUT_LOAD='(-0.01,0.01)';
      OUTPUT_LOAD='(1.0,-1.0)';
    '21':
      PIN_NUMBER='(21)';
      BIDIRECTIONAL='TRUE';
      INPUT_LOAD='(-0.01,0.01)';
      OUTPUT_LOAD='(1.0,-1.0)';
    '22':
      PIN_NUMBER='(22)';
      BIDIRECTIONAL='TRUE';
      INPUT_LOAD='(-0.01,0.01)';
      OUTPUT_LOAD='(1.0,-1.0)';
    '23':
      PIN_NUMBER='(23)';
      BIDIRECTIONAL='TRUE';
      INPUT_LOAD='(-0.01,0.01)';
      OUTPUT_LOAD='(1.0,-1.0)';
    '24':
      PIN_NUMBER='(24)';
      BIDIRECTIONAL='TRUE';
      INPUT_LOAD='(-0.01,0.01)';
      OUTPUT_LOAD='(1.0,-1.0)';
    '25':
      PIN_NUMBER='(25)';
      BIDIRECTIONAL='TRUE';
      INPUT_LOAD='(-0.01,0.01)';
      OUTPUT_LOAD='(1.0,-1.0)';
    '26':
      PIN_NUMBER='(26)';
      BIDIRECTIONAL='TRUE';
      INPUT_LOAD='(-0.01,0.01)';
      OUTPUT_LOAD='(1.0,-1.0)';
    '27':
      PIN_NUMBER='(27)';
      BIDIRECTIONAL='TRUE';
      INPUT_LOAD='(-0.01,0.01)';
      OUTPUT_LOAD='(1.0,-1.0)';
    '28':
      PIN_NUMBER='(28)';
      BIDIRECTIONAL='TRUE';
      INPUT_LOAD='(-0.01,0.01)';
      OUTPUT_LOAD='(1.0,-1.0)';
    '30':
      PIN_NUMBER='(30)';
      BIDIRECTIONAL='TRUE';
      INPUT_LOAD='(-0.01,0.01)';
      OUTPUT_LOAD='(1.0,-1.0)';
    '29':
      PIN_NUMBER='(29)';
      BIDIRECTIONAL='TRUE';
      INPUT_LOAD='(-0.01,0.01)';
      OUTPUT_LOAD='(1.0,-1.0)';
    '31':
      PIN_NUMBER='(31)';
      BIDIRECTIONAL='TRUE';
      INPUT_LOAD='(-0.01,0.01)';
      OUTPUT_LOAD='(1.0,-1.0)';
    '32':
      PIN_NUMBER='(32)';
      BIDIRECTIONAL='TRUE';
      INPUT_LOAD='(-0.01,0.01)';
      OUTPUT_LOAD='(1.0,-1.0)';
    '33':
      PIN_NUMBER='(33)';
      BIDIRECTIONAL='TRUE';
      INPUT_LOAD='(-0.01,0.01)';
      OUTPUT_LOAD='(1.0,-1.0)';
    '34':
      PIN_NUMBER='(34)';
      BIDIRECTIONAL='TRUE';
      INPUT_LOAD='(-0.01,0.01)';
      OUTPUT_LOAD='(1.0,-1.0)';
    '35':
      PIN_NUMBER='(35)';
      BIDIRECTIONAL='TRUE';
      INPUT_LOAD='(-0.01,0.01)';
      OUTPUT_LOAD='(1.0,-1.0)';
    '36':
      PIN_NUMBER='(36)';
      BIDIRECTIONAL='TRUE';
      INPUT_LOAD='(-0.01,0.01)';
      OUTPUT_LOAD='(1.0,-1.0)';
    '37':
      PIN_NUMBER='(37)';
      BIDIRECTIONAL='TRUE';
      INPUT_LOAD='(-0.01,0.01)';
      OUTPUT_LOAD='(1.0,-1.0)';
    '38':
      PIN_NUMBER='(38)';
      BIDIRECTIONAL='TRUE';
      INPUT_LOAD='(-0.01,0.01)';
      OUTPUT_LOAD='(1.0,-1.0)';
    '39':
      PIN_NUMBER='(39)';
      BIDIRECTIONAL='TRUE';
      INPUT_LOAD='(-0.01,0.01)';
      OUTPUT_LOAD='(1.0,-1.0)';
    '40':
      PIN_NUMBER='(40)';
      BIDIRECTIONAL='TRUE';
      INPUT_LOAD='(-0.01,0.01)';
      OUTPUT_LOAD='(1.0,-1.0)';
    '41':
      PIN_NUMBER='(41)';
      BIDIRECTIONAL='TRUE';
      INPUT_LOAD='(-0.01,0.01)';
      OUTPUT_LOAD='(1.0,-1.0)';
    '42':
      PIN_NUMBER='(42)';
      BIDIRECTIONAL='TRUE';
      INPUT_LOAD='(-0.01,0.01)';
      OUTPUT_LOAD='(1.0,-1.0)';
    '43':
      PIN_NUMBER='(43)';
      BIDIRECTIONAL='TRUE';
      INPUT_LOAD='(-0.01,0.01)';
      OUTPUT_LOAD='(1.0,-1.0)';
    '44':
      PIN_NUMBER='(44)';
      BIDIRECTIONAL='TRUE';
      INPUT_LOAD='(-0.01,0.01)';
      OUTPUT_LOAD='(1.0,-1.0)';
    '45':
      PIN_NUMBER='(45)';
      BIDIRECTIONAL='TRUE';
      INPUT_LOAD='(-0.01,0.01)';
      OUTPUT_LOAD='(1.0,-1.0)';
    '46':
      PIN_NUMBER='(46)';
      BIDIRECTIONAL='TRUE';
      INPUT_LOAD='(-0.01,0.01)';
      OUTPUT_LOAD='(1.0,-1.0)';
    '47':
      PIN_NUMBER='(47)';
      BIDIRECTIONAL='TRUE';
      INPUT_LOAD='(-0.01,0.01)';
      OUTPUT_LOAD='(1.0,-1.0)';
    '48':
      PIN_NUMBER='(48)';
      BIDIRECTIONAL='TRUE';
      INPUT_LOAD='(-0.01,0.01)';
      OUTPUT_LOAD='(1.0,-1.0)';
    '49':
      PIN_NUMBER='(49)';
      BIDIRECTIONAL='TRUE';
      INPUT_LOAD='(-0.01,0.01)';
      OUTPUT_LOAD='(1.0,-1.0)';
    '50':
      PIN_NUMBER='(50)';
      BIDIRECTIONAL='TRUE';
      INPUT_LOAD='(-0.01,0.01)';
      OUTPUT_LOAD='(1.0,-1.0)';
    '51':
      PIN_NUMBER='(51)';
      BIDIRECTIONAL='TRUE';
      INPUT_LOAD='(-0.01,0.01)';
      OUTPUT_LOAD='(1.0,-1.0)';
    '52':
      PIN_NUMBER='(52)';
      BIDIRECTIONAL='TRUE';
      INPUT_LOAD='(-0.01,0.01)';
      OUTPUT_LOAD='(1.0,-1.0)';
    '53':
      PIN_NUMBER='(53)';
      BIDIRECTIONAL='TRUE';
      INPUT_LOAD='(-0.01,0.01)';
      OUTPUT_LOAD='(1.0,-1.0)';
    '54':
      PIN_NUMBER='(54)';
      BIDIRECTIONAL='TRUE';
      INPUT_LOAD='(-0.01,0.01)';
      OUTPUT_LOAD='(1.0,-1.0)';
    '55':
      PIN_NUMBER='(55)';
      BIDIRECTIONAL='TRUE';
      INPUT_LOAD='(-0.01,0.01)';
      OUTPUT_LOAD='(1.0,-1.0)';
    '56':
      PIN_NUMBER='(56)';
      BIDIRECTIONAL='TRUE';
      INPUT_LOAD='(-0.01,0.01)';
      OUTPUT_LOAD='(1.0,-1.0)';
    '57':
      PIN_NUMBER='(57)';
      BIDIRECTIONAL='TRUE';
      INPUT_LOAD='(-0.01,0.01)';
      OUTPUT_LOAD='(1.0,-1.0)';
    '58':
      PIN_NUMBER='(58)';
      BIDIRECTIONAL='TRUE';
      INPUT_LOAD='(-0.01,0.01)';
      OUTPUT_LOAD='(1.0,-1.0)';
    '59':
      PIN_NUMBER='(59)';
      BIDIRECTIONAL='TRUE';
      INPUT_LOAD='(-0.01,0.01)';
      OUTPUT_LOAD='(1.0,-1.0)';
    '60':
      PIN_NUMBER='(60)';
      BIDIRECTIONAL='TRUE';
      INPUT_LOAD='(-0.01,0.01)';
      OUTPUT_LOAD='(1.0,-1.0)';
    'G1':
      PIN_NUMBER='(G1)';
      PINUSE='POWER';
      NO_LOAD_CHECK='Both';
      NO_IO_CHECK='Both';
      NO_ASSERT_CHECK='TRUE';
      NO_DIR_CHECK='TRUE';
      ALLOW_CONNECT='TRUE';
    'G2':
      PIN_NUMBER='(G2)';
      PINUSE='POWER';
      NO_LOAD_CHECK='Both';
      NO_IO_CHECK='Both';
      NO_ASSERT_CHECK='TRUE';
      NO_DIR_CHECK='TRUE';
      ALLOW_CONNECT='TRUE';
    'G3':
      PIN_NUMBER='(G3)';
      PINUSE='POWER';
      NO_LOAD_CHECK='Both';
      NO_IO_CHECK='Both';
      NO_ASSERT_CHECK='TRUE';
      NO_DIR_CHECK='TRUE';
      ALLOW_CONNECT='TRUE';
    'G4':
      PIN_NUMBER='(G4)';
      PINUSE='POWER';
      NO_LOAD_CHECK='Both';
      NO_IO_CHECK='Both';
      NO_ASSERT_CHECK='TRUE';
      NO_DIR_CHECK='TRUE';
      ALLOW_CONNECT='TRUE';
  end_pin;
  body
    PART_NAME='SCONN60_ASP21410801';
    BODY_NAME='SCONN60_ASP21410801';
    PHYS_DES_PREFIX='J';
    CLASS='IO';
    NC_PINS='(H1,H2)';
  end_body;
end_primitive;

END.
